# T6G (Grand Teton) — schematic netlist excerpt (pin names and nets, part order shuffled) for the footprints in the layout excerpt that follows; sources: Cadence DE-HDL packaged netlist, KiCad conversion of 04192023_DAF0TMB3IC0_F0TG_MB_C_brd_V02_OCP.brd

C6732  Q_CAP_DIFFBUS  DIFF BUS_0.22UF 6.3V 20% X6S  pkg C0201  page 352 : \1\ = P5E_CPU1_P3_TX_BUF_C_DN<3> ; \2\ = P5E_CPU1_P3_TX_BUF_DN<3>
C160  Q_CAP  0.1UF 25V 10% X7R  pkg 0402  page 104 : A = P3V3_AUX ; B = GND
PC264_1  Q_CAP  22UF 16V 20% X6S  pkg C0805  page 211 : A = SW_P12V_AUX_PVDDCR_CPU0_P1_FLT ; B = GND
C1057  Q_CAP  0.1UF 10V 10% X7S  pkg C0201  page 311 : A = P1V8_CPU0_RT_1D ; B = GND

(kicad_pcb
	(version 20260206)
	(generator "pcbnew")
	(generator_version "10.0")
	(general
		(thickness 1.6)
		(legacy_teardrops no)
	)
	(paper "A4")
	(title_block
		(title "04192023_DAF0TMB3IC0_F0TG_MB_C_brd_V02_OCP.brd")
		(comment 1 "Grand Teton / footprints 7482-7485 of 8354")
	)
	(layers
		(0 "F.Cu" signal "TOP")
		(4 "In1.Cu" signal "GND")
		(6 "In2.Cu" signal "IN1")
		(8 "In3.Cu" signal "GND1")
		(10 "In4.Cu" signal "IN2")
		(12 "In5.Cu" signal "GND2")
		(14 "In6.Cu" signal "IN3")
		(16 "In7.Cu" signal "GND3")
		(18 "In8.Cu" signal "VCC")
		(20 "In9.Cu" signal "VCC1")
		(22 "In10.Cu" signal "GND4")
		(24 "In11.Cu" signal "IN4")
		(26 "In12.Cu" signal "GND5")
		(28 "In13.Cu" signal "IN5")
		(30 "In14.Cu" signal "GND6")
		(32 "In15.Cu" signal "IN6")
		(34 "In16.Cu" signal "GND7")
		(2 "B.Cu" signal "BOTTOM")
		(9 "F.Adhes" user "F.Adhesive")
		(11 "B.Adhes" user "B.Adhesive")
		(13 "F.Paste" user "Package Geometry/Pastemask Top")
		(15 "B.Paste" user "Package Geometry/Pastemask Bottom")
		(5 "F.SilkS" user "Ref Des/Silkscreen Top")
		(7 "B.SilkS" user "Ref Des/Silkscreen Bottom")
		(1 "F.Mask" user "Board Geometry/Soldermask Top")
		(3 "B.Mask" user "Board Geometry/Soldermask Bottom")
		(17 "Dwgs.User" user "User.Drawings")
		(19 "Cmts.User" user "User.Comments")
		(21 "Eco1.User" user "User.Eco1")
		(23 "Eco2.User" user "User.Eco2")
		(25 "Edge.Cuts" user "Board Geometry/Outline")
		(27 "Margin" user)
		(31 "F.CrtYd" user "Package Geometry/Place Bound Top")
		(29 "B.CrtYd" user "Package Geometry/Place Bound Bottom")
		(35 "F.Fab" user "Ref Des/Assembly Top")
		(33 "B.Fab" user "Ref Des/Assembly Bottom")
	)
	(footprint ""
		(layer "B.Cu")
		(at 167.772334 -193.996564)
		(property "Reference" "C160"
			(at 0 0 0)
			(layer "B.SilkS")
			(hide yes)
			(effects
				(font
					(size 1.27 1.27)
				)
				(justify mirror)
			)
		)
		(property "Value" ""
			(at 0 0 0)
			(layer "B.Fab")
			(effects
				(font
					(size 1.27 1.27)
				)
				(justify mirror)
			)
		)
		(duplicate_pad_numbers_are_jumpers no)
		(fp_line
			(start -0.7874 -0.4064)
			(end -0.7874 0.4064)
			(stroke
				(width 0.1524)
				(type default)
			)
			(layer "B.SilkS")
		)
		(fp_line
			(start -0.7874 0.4064)
			(end 0.7874 0.4064)
			(stroke
				(width 0.1524)
				(type default)
			)
			(layer "B.SilkS")
		)
		(fp_line
			(start 0.7874 -0.4064)
			(end -0.7874 -0.4064)
			(stroke
				(width 0.1524)
				(type default)
			)
			(layer "B.SilkS")
		)
		(fp_line
			(start 0.7874 0.4064)
			(end 0.7874 -0.4064)
			(stroke
				(width 0.1524)
				(type default)
			)
			(layer "B.SilkS")
		)
		(fp_line
			(start -0.67945 -0.3048)
			(end -0.67945 0.3048)
			(stroke
				(width 0.1)
				(type default)
			)
			(layer "B.Fab")
		)
		(fp_line
			(start -0.67945 0.3048)
			(end -0.120396 0.3048)
			(stroke
				(width 0.1)
				(type default)
			)
			(layer "B.Fab")
		)
		(fp_line
			(start -0.12065 -0.3048)
			(end -0.67945 -0.3048)
			(stroke
				(width 0.1)
				(type default)
			)
			(layer "B.Fab")
		)
		(fp_line
			(start -0.12065 -0.2794)
			(end -0.12065 -0.3048)
			(stroke
				(width 0.1)
				(type default)
			)
			(layer "B.Fab")
		)
		(fp_line
			(start -0.120396 0.2794)
			(end 0.12065 0.2794)
			(stroke
				(width 0.1)
				(type default)
			)
			(layer "B.Fab")
		)
		(fp_line
			(start -0.120396 0.3048)
			(end -0.120396 0.2794)
			(stroke
				(width 0.1)
				(type default)
			)
			(layer "B.Fab")
		)
		(fp_line
			(start 0.12065 -0.305054)
			(end 0.12065 -0.2794)
			(stroke
				(width 0.1)
				(type default)
			)
			(layer "B.Fab")
		)
		(fp_line
			(start 0.12065 -0.2794)
			(end -0.12065 -0.2794)
			(stroke
				(width 0.1)
				(type default)
			)
			(layer "B.Fab")
		)
		(fp_line
			(start 0.12065 0.2794)
			(end 0.12065 0.3048)
			(stroke
				(width 0.1)
				(type default)
			)
			(layer "B.Fab")
		)
		(fp_line
			(start 0.12065 0.3048)
			(end 0.67945 0.3048)
			(stroke
				(width 0.1)
				(type default)
			)
			(layer "B.Fab")
		)
		(fp_line
			(start 0.67945 -0.305054)
			(end 0.12065 -0.305054)
			(stroke
				(width 0.1)
				(type default)
			)
			(layer "B.Fab")
		)
		(fp_line
			(start 0.67945 0.3048)
			(end 0.67945 -0.305054)
			(stroke
				(width 0.1)
				(type default)
			)
			(layer "B.Fab")
		)
		(pad "1" smd circle
			(at 0.40005 0 180)
			(size 0 0)
			(layers "B.Cu" "B.Mask" "B.Paste")
			(net "P3V3_AUX")
		)
		(pad "2" smd circle
			(at -0.40005 0 180)
			(size 0 0)
			(layers "B.Cu" "B.Mask" "B.Paste")
			(net "GND")
		)
	)
	(footprint ""
		(layer "B.Cu")
		(at 80.937354 -178.962812 90)
		(property "Reference" "PC264_1"
			(at 0 0 90)
			(layer "B.SilkS")
			(hide yes)
			(effects
				(font
					(size 1.27 1.27)
				)
				(justify mirror)
			)
		)
		(property "Value" ""
			(at 0 0 90)
			(layer "B.Fab")
			(effects
				(font
					(size 1.27 1.27)
				)
				(justify mirror)
			)
		)
		(duplicate_pad_numbers_are_jumpers no)
		(fp_line
			(start 1.524 -0.762)
			(end -1.524 -0.762)
			(stroke
				(width 0.1524)
				(type default)
			)
			(layer "B.SilkS")
		)
		(fp_line
			(start -1.524 -0.762)
			(end -1.524 0.762)
			(stroke
				(width 0.1524)
				(type default)
			)
			(layer "B.SilkS")
		)
		(fp_line
			(start 1.524 0.762)
			(end 1.524 -0.762)
			(stroke
				(width 0.1524)
				(type default)
			)
			(layer "B.SilkS")
		)
		(fp_line
			(start -1.524 0.762)
			(end 1.524 0.762)
			(stroke
				(width 0.1524)
				(type default)
			)
			(layer "B.SilkS")
		)
		(fp_line
			(start 1.1049 -0.724916)
			(end 1.1049 0.724916)
			(stroke
				(width 0.1)
				(type default)
			)
			(layer "B.Fab")
		)
		(fp_line
			(start -1.1049 -0.724916)
			(end 1.1049 -0.724916)
			(stroke
				(width 0.1)
				(type default)
			)
			(layer "B.Fab")
		)
		(fp_line
			(start 1.1049 0.724916)
			(end -1.1049 0.724916)
			(stroke
				(width 0.1)
				(type default)
			)
			(layer "B.Fab")
		)
		(fp_line
			(start -1.1049 0.724916)
			(end -1.1049 -0.724916)
			(stroke
				(width 0.1)
				(type default)
			)
			(layer "B.Fab")
		)
		(pad "1" smd rect
			(at 0.889 0 90)
			(size 1.016 1.27)
			(layers "B.Cu" "B.Mask" "B.Paste")
			(net "SW_P12V_AUX_PVDDCR_CPU0_P1_FLT")
		)
		(pad "2" smd rect
			(at -0.889 0 90)
			(size 1.016 1.27)
			(layers "B.Cu" "B.Mask" "B.Paste")
			(net "GND")
		)
	)
	(footprint ""
		(layer "B.Cu")
		(at 125.590046 -408.517344 90)
		(property "Reference" "C6732"
			(at 0 0 90)
			(layer "B.SilkS")
			(hide yes)
			(effects
				(font
					(size 1.27 1.27)
				)
				(justify mirror)
			)
		)
		(property "Value" ""
			(at 0 0 90)
			(layer "B.Fab")
			(effects
				(font
					(size 1.27 1.27)
				)
				(justify mirror)
			)
		)
		(duplicate_pad_numbers_are_jumpers no)
		(fp_line
			(start 0.299974 -0.150114)
			(end -0.299974 -0.150114)
			(stroke
				(width 0.1)
				(type default)
			)
			(layer "B.Fab")
		)
		(fp_line
			(start -0.299974 -0.150114)
			(end -0.299974 0.150114)
			(stroke
				(width 0.1)
				(type default)
			)
			(layer "B.Fab")
		)
		(fp_line
			(start 0.299974 0.150114)
			(end 0.299974 -0.150114)
			(stroke
				(width 0.1)
				(type default)
			)
			(layer "B.Fab")
		)
		(fp_line
			(start -0.299974 0.150114)
			(end 0.299974 0.150114)
			(stroke
				(width 0.1)
				(type default)
			)
			(layer "B.Fab")
		)
		(pad "1" smd rect
			(at 0.2667 0 270)
			(size 0.3048 0.381)
			(layers "B.Cu" "B.Mask" "B.Paste")
			(net "P5E_CPU1_P3_TX_BUF_C_DN<3>")
		)
		(pad "2" smd rect
			(at -0.2667 0 270)
			(size 0.3048 0.381)
			(layers "B.Cu" "B.Mask" "B.Paste")
			(net "P5E_CPU1_P3_TX_BUF_DN<3>")
		)
	)
	(footprint ""
		(layer "B.Cu")
		(at 369.57 -426.466)
		(property "Reference" "C1057"
			(at 0 0 0)
			(layer "B.SilkS")
			(hide yes)
			(effects
				(font
					(size 1.27 1.27)
				)
				(justify mirror)
			)
		)
		(property "Value" ""
			(at 0 0 0)
			(layer "B.Fab")
			(effects
				(font
					(size 1.27 1.27)
				)
				(justify mirror)
			)
		)
		(duplicate_pad_numbers_are_jumpers no)
		(fp_line
			(start -0.299974 -0.150114)
			(end -0.299974 0.150114)
			(stroke
				(width 0.1)
				(type default)
			)
			(layer "B.Fab")
		)
		(fp_line
			(start -0.299974 0.150114)
			(end 0.299974 0.150114)
			(stroke
				(width 0.1)
				(type default)
			)
			(layer "B.Fab")
		)
		(fp_line
			(start 0.299974 -0.150114)
			(end -0.299974 -0.150114)
			(stroke
				(width 0.1)
				(type default)
			)
			(layer "B.Fab")
		)
		(fp_line
			(start 0.299974 0.150114)
			(end 0.299974 -0.150114)
			(stroke
				(width 0.1)
				(type default)
			)
			(layer "B.Fab")
		)
		(pad "1" smd rect
			(at 0.2667 0 180)
			(size 0.3048 0.381)
			(layers "B.Cu" "B.Mask" "B.Paste")
			(net "P1V8_CPU0_RT_1D")
		)
		(pad "2" smd rect
			(at -0.2667 0 180)
			(size 0.3048 0.381)
			(layers "B.Cu" "B.Mask" "B.Paste")
			(net "GND")
		)
	)
)
